(kicad_pcb
	(version 20260206)
	(generator "pcbnew")
	(generator_version "10.0")
	(general
		(thickness 1.6)
		(legacy_teardrops no)
	)
	(paper "A4")
	(title_block
		(title "Wiwynn_Tioga_Pass_MB.brd")
		(comment 1 "Tioga Pass / footprints 4623-4629 of 4770")
	)
	(layers
		(0 "F.Cu" signal "TOP")
		(4 "In1.Cu" signal "L2GND")
		(6 "In2.Cu" signal "L3")
		(8 "In3.Cu" signal "L4GND")
		(10 "In4.Cu" signal "L5")
		(12 "In5.Cu" signal "L6GND")
		(14 "In6.Cu" signal "L7VCC")
		(16 "In7.Cu" signal "L8VCC")
		(18 "In8.Cu" signal "L9GND")
		(20 "In9.Cu" signal "L10")
		(22 "In10.Cu" signal "L11GND")
		(24 "In11.Cu" signal "L12")
		(26 "In12.Cu" signal "L13GND")
		(2 "B.Cu" signal "BOTTOM")
		(9 "F.Adhes" user "F.Adhesive")
		(11 "B.Adhes" user "B.Adhesive")
		(13 "F.Paste" user "Package Geometry/Pastemask Top")
		(15 "B.Paste" user "Package Geometry/Pastemask Bottom")
		(5 "F.SilkS" user "Ref Des/Silkscreen Top")
		(7 "B.SilkS" user "Ref Des/Silkscreen Bottom")
		(1 "F.Mask" user "Board Geometry/Soldermask Top")
		(3 "B.Mask" user "Board Geometry/Soldermask Bottom")
		(17 "Dwgs.User" user "User.Drawings")
		(19 "Cmts.User" user "User.Comments")
		(21 "Eco1.User" user "User.Eco1")
		(23 "Eco2.User" user "User.Eco2")
		(25 "Edge.Cuts" user "Board Geometry/Outline")
		(27 "Margin" user)
		(31 "F.CrtYd" user "Package Geometry/Place Bound Top")
		(29 "B.CrtYd" user "Package Geometry/Place Bound Bottom")
		(35 "F.Fab" user "Ref Des/Assembly Top")
		(33 "B.Fab" user "Ref Des/Assembly Bottom")
	)
	(footprint ""
		(layer "B.Cu")
		(at 401.472146 -41.360852 90)
		(property "Reference" "R8F23"
			(at 0 0 90)
			(layer "B.SilkS")
			(hide yes)
			(effects
				(font
					(size 1.27 1.27)
				)
				(justify mirror)
			)
		)
		(property "Value" ""
			(at 0 0 90)
			(layer "B.Fab")
			(effects
				(font
					(size 1.27 1.27)
				)
				(justify mirror)
			)
		)
		(duplicate_pad_numbers_are_jumpers no)
		(fp_poly
			(pts
				(xy 0.2794 -0.1016) (xy -0.2794 -0.1016) (xy -0.2794 0.9906) (xy 0.2794 0.9906)
			)
			(stroke
				(width 0)
				(type default)
			)
			(fill no)
			(layer "B.CrtYd")
		)
		(fp_line
			(start 0.2794 -0.1016)
			(end 0.2794 0.9906)
			(stroke
				(width 0.1)
				(type default)
			)
			(layer "B.Fab")
		)
		(fp_line
			(start -0.2794 -0.1016)
			(end 0.2794 -0.1016)
			(stroke
				(width 0.1)
				(type default)
			)
			(layer "B.Fab")
		)
		(fp_line
			(start 0.2794 0.9906)
			(end -0.2794 0.9906)
			(stroke
				(width 0.1)
				(type default)
			)
			(layer "B.Fab")
		)
		(fp_line
			(start -0.2794 0.9906)
			(end -0.2794 -0.1016)
			(stroke
				(width 0.1)
				(type default)
			)
			(layer "B.Fab")
		)
		(pad "1" smd rect
			(at 0 0 270)
			(size 0.508 0.508)
			(layers "B.Cu" "B.Mask" "B.Paste")
			(net "P3V3_STBY")
		)
		(pad "2" smd rect
			(at 0 0.889 270)
			(size 0.508 0.508)
			(layers "B.Cu" "B.Mask" "B.Paste")
			(net "IRQ_MEZZ_LAN_ALERT_N")
		)
		(zone
			(layer "B.Cu")
			(hatch none 0.5)
			(connect_pads
				(clearance 0)
			)
			(min_thickness 0.25)
			(keepout
				(tracks allowed)
				(vias not_allowed)
				(pads allowed)
				(copperpour not_allowed)
				(footprints allowed)
			)
			(placement
				(enabled no)
				(sheetname "")
			)
			(fill
				(thermal_gap 0.5)
				(thermal_bridge_width 0.5)
				(island_removal_mode 0)
			)
			(polygon
				(pts
					(xy 401.726146 -41.614852) (xy 401.726146 -41.106852) (xy 402.107146 -41.106852) (xy 402.107146 -41.614852)
				)
			)
		)
		(zone
			(layer "B.Cu")
			(hatch none 0.5)
			(connect_pads
				(clearance 0)
			)
			(min_thickness 0.25)
			(keepout
				(tracks not_allowed)
				(vias allowed)
				(pads allowed)
				(copperpour not_allowed)
				(footprints allowed)
			)
			(placement
				(enabled no)
				(sheetname "")
			)
			(fill
				(thermal_gap 0.5)
				(thermal_bridge_width 0.5)
				(island_removal_mode 0)
			)
			(polygon
				(pts
					(xy 402.107146 -41.614852) (xy 402.107146 -41.106852) (xy 401.726146 -41.106852) (xy 401.726146 -41.614852)
				)
			)
		)
	)
	(footprint ""
		(layer "B.Cu")
		(at 483.6795 -139.5095 180)
		(property "Reference" "Q1L3"
			(at -2.48285 0.50546 90)
			(unlocked yes)
			(layer "B.SilkS")
			(effects
				(font
					(size 0.7874 0.5842)
					(thickness 0.1524)
				)
				(justify left mirror)
			)
		)
		(property "Value" ""
			(at 0 0 0)
			(layer "B.Fab")
			(effects
				(font
					(size 1.27 1.27)
				)
				(justify mirror)
			)
		)
		(duplicate_pad_numbers_are_jumpers no)
		(fp_line
			(start -0.381 0.635)
			(end -0.381 1.27)
			(stroke
				(width 0.1524)
				(type default)
			)
			(layer "B.SilkS")
		)
		(fp_line
			(start -0.9525 2.4765)
			(end -1.778 2.4765)
			(stroke
				(width 0.1524)
				(type default)
			)
			(layer "B.SilkS")
		)
		(fp_line
			(start -0.9525 -0.5715)
			(end -1.778 -0.5715)
			(stroke
				(width 0.1524)
				(type default)
			)
			(layer "B.SilkS")
		)
		(fp_line
			(start -1.778 2.4765)
			(end -1.778 1.5875)
			(stroke
				(width 0.1524)
				(type default)
			)
			(layer "B.SilkS")
		)
		(fp_line
			(start -1.778 -0.5715)
			(end -1.778 0.3175)
			(stroke
				(width 0.1524)
				(type default)
			)
			(layer "B.SilkS")
		)
		(fp_circle
			(center 0.9525 -0.9271)
			(end 0.8255 -0.9271)
			(stroke
				(width 0.254)
				(type default)
			)
			(fill no)
			(layer "B.SilkS")
		)
		(fp_poly
			(pts
				(xy -1.778 2.4765) (xy -0.381 2.4765) (xy -0.381 -0.5715) (xy -1.778 -0.5715)
			)
			(stroke
				(width 0)
				(type default)
			)
			(fill no)
			(layer "B.CrtYd")
		)
		(fp_line
			(start -0.381 2.4765)
			(end -1.778 2.4765)
			(stroke
				(width 0.1)
				(type default)
			)
			(layer "B.Fab")
		)
		(fp_line
			(start -0.381 -0.5715)
			(end -0.381 2.4765)
			(stroke
				(width 0.1)
				(type default)
			)
			(layer "B.Fab")
		)
		(fp_line
			(start -1.778 2.4765)
			(end -1.778 -0.5715)
			(stroke
				(width 0.1)
				(type default)
			)
			(layer "B.Fab")
		)
		(fp_line
			(start -1.778 -0.5715)
			(end -0.381 -0.5715)
			(stroke
				(width 0.1)
				(type default)
			)
			(layer "B.Fab")
		)
		(fp_circle
			(center 0.9525 -0.9271)
			(end 0.8255 -0.9271)
			(stroke
				(width 0.254)
				(type default)
			)
			(fill no)
			(layer "B.Fab")
		)
		(pad "1" smd rect
			(at 0 0)
			(size 1.143 0.508)
			(layers "B.Cu" "B.Mask" "B.Paste")
			(net "FM_DB_UART_SEL4_N")
		)
		(pad "2" smd rect
			(at 0 1.905)
			(size 1.143 0.508)
			(layers "B.Cu" "B.Mask" "B.Paste")
			(net "GND")
		)
		(pad "3" smd rect
			(at -2.159 0.9525)
			(size 1.143 0.508)
			(layers "B.Cu" "B.Mask" "B.Paste")
			(net "FM_DB_PRESENT")
		)
	)
	(footprint ""
		(layer "B.Cu")
		(at 279.896824 -70.673214 90)
		(property "Reference" "R4P14"
			(at 0 0 90)
			(layer "B.SilkS")
			(hide yes)
			(effects
				(font
					(size 1.27 1.27)
				)
				(justify mirror)
			)
		)
		(property "Value" ""
			(at 0 0 90)
			(layer "B.Fab")
			(effects
				(font
					(size 1.27 1.27)
				)
				(justify mirror)
			)
		)
		(duplicate_pad_numbers_are_jumpers no)
		(fp_poly
			(pts
				(xy 0.2794 -0.1016) (xy -0.2794 -0.1016) (xy -0.2794 0.9906) (xy 0.2794 0.9906)
			)
			(stroke
				(width 0)
				(type default)
			)
			(fill no)
			(layer "B.CrtYd")
		)
		(fp_line
			(start 0.2794 -0.1016)
			(end 0.2794 0.9906)
			(stroke
				(width 0.1)
				(type default)
			)
			(layer "B.Fab")
		)
		(fp_line
			(start -0.2794 -0.1016)
			(end 0.2794 -0.1016)
			(stroke
				(width 0.1)
				(type default)
			)
			(layer "B.Fab")
		)
		(fp_line
			(start 0.2794 0.9906)
			(end -0.2794 0.9906)
			(stroke
				(width 0.1)
				(type default)
			)
			(layer "B.Fab")
		)
		(fp_line
			(start -0.2794 0.9906)
			(end -0.2794 -0.1016)
			(stroke
				(width 0.1)
				(type default)
			)
			(layer "B.Fab")
		)
		(pad "1" smd rect
			(at 0 0 270)
			(size 0.508 0.508)
			(layers "B.Cu" "B.Mask" "B.Paste")
			(net "PVCCIO_CPU0")
		)
		(pad "2" smd rect
			(at 0 0.889 270)
			(size 0.508 0.508)
			(layers "B.Cu" "B.Mask" "B.Paste")
			(net "PU_CPU0_LEGACY_SKT")
		)
		(zone
			(layer "B.Cu")
			(hatch none 0.5)
			(connect_pads
				(clearance 0)
			)
			(min_thickness 0.25)
			(keepout
				(tracks allowed)
				(vias not_allowed)
				(pads allowed)
				(copperpour not_allowed)
				(footprints allowed)
			)
			(placement
				(enabled no)
				(sheetname "")
			)
			(fill
				(thermal_gap 0.5)
				(thermal_bridge_width 0.5)
				(island_removal_mode 0)
			)
			(polygon
				(pts
					(xy 280.150824 -70.927214) (xy 280.150824 -70.419214) (xy 280.531824 -70.419214) (xy 280.531824 -70.927214)
				)
			)
		)
		(zone
			(layer "B.Cu")
			(hatch none 0.5)
			(connect_pads
				(clearance 0)
			)
			(min_thickness 0.25)
			(keepout
				(tracks not_allowed)
				(vias allowed)
				(pads allowed)
				(copperpour not_allowed)
				(footprints allowed)
			)
			(placement
				(enabled no)
				(sheetname "")
			)
			(fill
				(thermal_gap 0.5)
				(thermal_bridge_width 0.5)
				(island_removal_mode 0)
			)
			(polygon
				(pts
					(xy 280.531824 -70.927214) (xy 280.531824 -70.419214) (xy 280.150824 -70.419214) (xy 280.150824 -70.927214)
				)
			)
		)
	)
	(footprint ""
		(layer "B.Cu")
		(at 411.9626 -121.9962 180)
		(property "Reference" "C8B16"
			(at 0 0 0)
			(layer "B.SilkS")
			(hide yes)
			(effects
				(font
					(size 1.27 1.27)
				)
				(justify mirror)
			)
		)
		(property "Value" ""
			(at 0 0 0)
			(layer "B.Fab")
			(effects
				(font
					(size 1.27 1.27)
				)
				(justify mirror)
			)
		)
		(duplicate_pad_numbers_are_jumpers no)
		(fp_rect
			(start -0.7239 1.9939)
			(end 0.7239 -0.2159)
			(stroke
				(width 0)
				(type default)
			)
			(fill no)
			(layer "B.CrtYd")
		)
		(fp_line
			(start 0.7239 1.9939)
			(end -0.7239 1.9939)
			(stroke
				(width 0.1)
				(type default)
			)
			(layer "B.Fab")
		)
		(fp_line
			(start 0.7239 -0.2159)
			(end 0.7239 1.9939)
			(stroke
				(width 0.1)
				(type default)
			)
			(layer "B.Fab")
		)
		(fp_line
			(start -0.7239 1.9939)
			(end -0.7239 -0.2159)
			(stroke
				(width 0.1)
				(type default)
			)
			(layer "B.Fab")
		)
		(fp_line
			(start -0.7239 -0.2159)
			(end 0.7239 -0.2159)
			(stroke
				(width 0.1)
				(type default)
			)
			(layer "B.Fab")
		)
		(pad "1" smd rect
			(at 0 0)
			(size 1.27 1.016)
			(layers "B.Cu" "B.Mask" "B.Paste")
			(net "P1V05_PCH_STBY")
		)
		(pad "2" smd rect
			(at 0 1.778)
			(size 1.27 1.016)
			(layers "B.Cu" "B.Mask" "B.Paste")
			(net "GND")
		)
		(zone
			(layer "B.Cu")
			(hatch none 0.5)
			(connect_pads
				(clearance 0)
			)
			(min_thickness 0.25)
			(keepout
				(tracks not_allowed)
				(vias allowed)
				(pads allowed)
				(copperpour not_allowed)
				(footprints allowed)
			)
			(placement
				(enabled no)
				(sheetname "")
			)
			(fill
				(thermal_gap 0.5)
				(thermal_bridge_width 0.5)
				(island_removal_mode 0)
			)
			(polygon
				(pts
					(xy 412.5976 -123.2662) (xy 411.3276 -123.2662) (xy 411.3276 -122.5042) (xy 412.5976 -122.5042)
				)
			)
		)
	)
	(footprint ""
		(layer "B.Cu")
		(at 40.994838 -104.252776 90)
		(property "Reference" "R1C4"
			(at 0 0 90)
			(layer "B.SilkS")
			(hide yes)
			(effects
				(font
					(size 1.27 1.27)
				)
				(justify mirror)
			)
		)
		(property "Value" ""
			(at 0 0 90)
			(layer "B.Fab")
			(effects
				(font
					(size 1.27 1.27)
				)
				(justify mirror)
			)
		)
		(duplicate_pad_numbers_are_jumpers no)
		(fp_poly
			(pts
				(xy 0.2794 -0.1016) (xy -0.2794 -0.1016) (xy -0.2794 0.9906) (xy 0.2794 0.9906)
			)
			(stroke
				(width 0)
				(type default)
			)
			(fill no)
			(layer "B.CrtYd")
		)
		(fp_line
			(start 0.2794 -0.1016)
			(end 0.2794 0.9906)
			(stroke
				(width 0.1)
				(type default)
			)
			(layer "B.Fab")
		)
		(fp_line
			(start -0.2794 -0.1016)
			(end 0.2794 -0.1016)
			(stroke
				(width 0.1)
				(type default)
			)
			(layer "B.Fab")
		)
		(fp_line
			(start 0.2794 0.9906)
			(end -0.2794 0.9906)
			(stroke
				(width 0.1)
				(type default)
			)
			(layer "B.Fab")
		)
		(fp_line
			(start -0.2794 0.9906)
			(end -0.2794 -0.1016)
			(stroke
				(width 0.1)
				(type default)
			)
			(layer "B.Fab")
		)
		(pad "1" smd rect
			(at 0 0 270)
			(size 0.508 0.508)
			(layers "B.Cu" "B.Mask" "B.Paste")
			(net "VSENSE_PVSA_CPU1_N")
		)
		(pad "2" smd rect
			(at 0 0.889 270)
			(size 0.508 0.508)
			(layers "B.Cu" "B.Mask" "B.Paste")
			(net "GND")
		)
		(zone
			(layer "B.Cu")
			(hatch none 0.5)
			(connect_pads
				(clearance 0)
			)
			(min_thickness 0.25)
			(keepout
				(tracks allowed)
				(vias not_allowed)
				(pads allowed)
				(copperpour not_allowed)
				(footprints allowed)
			)
			(placement
				(enabled no)
				(sheetname "")
			)
			(fill
				(thermal_gap 0.5)
				(thermal_bridge_width 0.5)
				(island_removal_mode 0)
			)
			(polygon
				(pts
					(xy 41.248838 -104.506776) (xy 41.248838 -103.998776) (xy 41.629838 -103.998776) (xy 41.629838 -104.506776)
				)
			)
		)
		(zone
			(layer "B.Cu")
			(hatch none 0.5)
			(connect_pads
				(clearance 0)
			)
			(min_thickness 0.25)
			(keepout
				(tracks not_allowed)
				(vias allowed)
				(pads allowed)
				(copperpour not_allowed)
				(footprints allowed)
			)
			(placement
				(enabled no)
				(sheetname "")
			)
			(fill
				(thermal_gap 0.5)
				(thermal_bridge_width 0.5)
				(island_removal_mode 0)
			)
			(polygon
				(pts
					(xy 41.629838 -104.506776) (xy 41.629838 -103.998776) (xy 41.248838 -103.998776) (xy 41.248838 -104.506776)
				)
			)
		)
	)
	(footprint ""
		(layer "B.Cu")
		(at 378.587 -81.8896 -90)
		(property "Reference" "R7W2"
			(at 0.8382 -0.67818 270)
			(unlocked yes)
			(layer "B.SilkS")
			(effects
				(font
					(size 0.4064 0.254)
					(thickness 0.1524)
				)
				(justify left mirror)
			)
		)
		(property "Value" ""
			(at 0 0 90)
			(layer "B.Fab")
			(effects
				(font
					(size 1.27 1.27)
				)
				(justify mirror)
			)
		)
		(duplicate_pad_numbers_are_jumpers no)
		(fp_poly
			(pts
				(xy 0.2794 -0.1016) (xy -0.2794 -0.1016) (xy -0.2794 0.9906) (xy 0.2794 0.9906)
			)
			(stroke
				(width 0)
				(type default)
			)
			(fill no)
			(layer "B.CrtYd")
		)
		(fp_line
			(start -0.2794 0.9906)
			(end -0.2794 -0.1016)
			(stroke
				(width 0.1)
				(type default)
			)
			(layer "B.Fab")
		)
		(fp_line
			(start 0.2794 0.9906)
			(end -0.2794 0.9906)
			(stroke
				(width 0.1)
				(type default)
			)
			(layer "B.Fab")
		)
		(fp_line
			(start -0.2794 -0.1016)
			(end 0.2794 -0.1016)
			(stroke
				(width 0.1)
				(type default)
			)
			(layer "B.Fab")
		)
		(fp_line
			(start 0.2794 -0.1016)
			(end 0.2794 0.9906)
			(stroke
				(width 0.1)
				(type default)
			)
			(layer "B.Fab")
		)
		(pad "1" smd rect
			(at 0 0 90)
			(size 0.508 0.508)
			(layers "B.Cu" "B.Mask" "B.Paste")
			(net "PECI_CPU_G")
		)
		(pad "2" smd rect
			(at 0 0.889 90)
			(size 0.508 0.508)
			(layers "B.Cu" "B.Mask" "B.Paste")
			(net "GND")
		)
		(zone
			(layer "B.Cu")
			(hatch none 0.5)
			(connect_pads
				(clearance 0)
			)
			(min_thickness 0.25)
			(keepout
				(tracks not_allowed)
				(vias allowed)
				(pads allowed)
				(copperpour not_allowed)
				(footprints allowed)
			)
			(placement
				(enabled no)
				(sheetname "")
			)
			(fill
				(thermal_gap 0.5)
				(thermal_bridge_width 0.5)
				(island_removal_mode 0)
			)
			(polygon
				(pts
					(xy 377.952 -81.6356) (xy 377.952 -82.1436) (xy 378.333 -82.1436) (xy 378.333 -81.6356)
				)
			)
		)
		(zone
			(layer "B.Cu")
			(hatch none 0.5)
			(connect_pads
				(clearance 0)
			)
			(min_thickness 0.25)
			(keepout
				(tracks allowed)
				(vias not_allowed)
				(pads allowed)
				(copperpour not_allowed)
				(footprints allowed)
			)
			(placement
				(enabled no)
				(sheetname "")
			)
			(fill
				(thermal_gap 0.5)
				(thermal_bridge_width 0.5)
				(island_removal_mode 0)
			)
			(polygon
				(pts
					(xy 378.333 -81.6356) (xy 378.333 -82.1436) (xy 377.952 -82.1436) (xy 377.952 -81.6356)
				)
			)
		)
	)
	(footprint ""
		(layer "B.Cu")
		(at 464.4644 -134.366 180)
		(property "Reference" "R9B10"
			(at 0 0 0)
			(layer "B.SilkS")
			(hide yes)
			(effects
				(font
					(size 1.27 1.27)
				)
				(justify mirror)
			)
		)
		(property "Value" ""
			(at 0 0 0)
			(layer "B.Fab")
			(effects
				(font
					(size 1.27 1.27)
				)
				(justify mirror)
			)
		)
		(duplicate_pad_numbers_are_jumpers no)
		(fp_poly
			(pts
				(xy 0.2794 -0.1016) (xy -0.2794 -0.1016) (xy -0.2794 0.9906) (xy 0.2794 0.9906)
			)
			(stroke
				(width 0)
				(type default)
			)
			(fill no)
			(layer "B.CrtYd")
		)
		(fp_line
			(start 0.2794 0.9906)
			(end -0.2794 0.9906)
			(stroke
				(width 0.1)
				(type default)
			)
			(layer "B.Fab")
		)
		(fp_line
			(start 0.2794 -0.1016)
			(end 0.2794 0.9906)
			(stroke
				(width 0.1)
				(type default)
			)
			(layer "B.Fab")
		)
		(fp_line
			(start -0.2794 0.9906)
			(end -0.2794 -0.1016)
			(stroke
				(width 0.1)
				(type default)
			)
			(layer "B.Fab")
		)
		(fp_line
			(start -0.2794 -0.1016)
			(end 0.2794 -0.1016)
			(stroke
				(width 0.1)
				(type default)
			)
			(layer "B.Fab")
		)
		(pad "1" smd rect
			(at 0 0)
			(size 0.508 0.508)
			(layers "B.Cu" "B.Mask" "B.Paste")
			(net "JTAG_MCP_TCK")
		)
		(pad "2" smd rect
			(at 0 0.889)
			(size 0.508 0.508)
			(layers "B.Cu" "B.Mask" "B.Paste")
			(net "JTAG_MCP_TCK_R1")
		)
		(zone
			(layer "B.Cu")
			(hatch none 0.5)
			(connect_pads
				(clearance 0)
			)
			(min_thickness 0.25)
			(keepout
				(tracks not_allowed)
				(vias allowed)
				(pads allowed)
				(copperpour not_allowed)
				(footprints allowed)
			)
			(placement
				(enabled no)
				(sheetname "")
			)
			(fill
				(thermal_gap 0.5)
				(thermal_bridge_width 0.5)
				(island_removal_mode 0)
			)
			(polygon
				(pts
					(xy 464.2104 -135.001) (xy 464.7184 -135.001) (xy 464.7184 -134.62) (xy 464.2104 -134.62)
				)
			)
		)
		(zone
			(layer "B.Cu")
			(hatch none 0.5)
			(connect_pads
				(clearance 0)
			)
			(min_thickness 0.25)
			(keepout
				(tracks allowed)
				(vias not_allowed)
				(pads allowed)
				(copperpour not_allowed)
				(footprints allowed)
			)
			(placement
				(enabled no)
				(sheetname "")
			)
			(fill
				(thermal_gap 0.5)
				(thermal_bridge_width 0.5)
				(island_removal_mode 0)
			)
			(polygon
				(pts
					(xy 464.2104 -134.62) (xy 464.7184 -134.62) (xy 464.7184 -135.001) (xy 464.2104 -135.001)
				)
			)
		)
	)
)
